#ISCELL
  pure_quanta quanta_title_block_c *
  *
#CELL
  pure_quanta genoa_sp5 *
  page31_i19
#CELL
  pure_quanta genoa_sp5 *
  page31_i20
#CELL
  pure_quanta genoa_sp5 *
  page31_i21
#CELL
  pure_quanta genoa_sp5 *
  page31_i22
#CELL
  pure_quanta genoa_sp5 *
  page31_i23
#CELL
  pure_quanta genoa_sp5 *
  page31_i24
#ISCELL
  pure_quanta_power universal_gnd *
  page31_i39
#ISCELL
  pure_quanta_power universal_gnd *
  page31_i40
#ISCELL
  pure_quanta_power universal_gnd *
  page31_i41
#ISCELL
  pure_quanta_power universal_gnd *
  page31_i43
#ISCELL
  pure_quanta_power universal_gnd *
  page31_i44
#ISCELL
  pure_quanta_power universal_gnd *
  page31_i45
#ISCELL
  pure_quanta_power universal_gnd *
  page31_i46
#ISCELL
  pure_quanta_power universal_gnd *
  page31_i47
#ISCELL
  pure_quanta_power universal_gnd *
  page31_i48
#ISCELL
  pure_quanta_power universal_gnd *
  page31_i49
#ISCELL
  pure_quanta_power universal_gnd *
  page31_i50
#ISCELL
  pure_quanta_power universal_gnd *
  page31_i51
